(kicad_pcb
	(version 20260206)
	(generator "pcbnew")
	(generator_version "10.0")
	(general
		(thickness 1.6)
		(legacy_teardrops no)
	)
	(paper "A4")
	(title_block
		(title "01162023_DA0F0TEBIF0_F0T_Expander_BD_F_brd_V02_OCP.brd")
		(comment 1 "Grand Teton / footprints 590-597 of 9728")
	)
	(layers
		(0 "F.Cu" signal "TOP")
		(4 "In1.Cu" signal "GND")
		(6 "In2.Cu" signal "VCC")
		(8 "In3.Cu" signal "VCC1")
		(10 "In4.Cu" signal "GND1")
		(12 "In5.Cu" signal "IN1")
		(14 "In6.Cu" signal "GND2")
		(16 "In7.Cu" signal "IN2")
		(18 "In8.Cu" signal "GND3")
		(20 "In9.Cu" signal "IN3")
		(22 "In10.Cu" signal "GND4")
		(24 "In11.Cu" signal "IN4")
		(26 "In12.Cu" signal "GND5")
		(28 "In13.Cu" signal "IN5")
		(30 "In14.Cu" signal "GND6")
		(32 "In15.Cu" signal "IN6")
		(34 "In16.Cu" signal "GND7")
		(2 "B.Cu" signal "BOTTOM")
		(9 "F.Adhes" user "F.Adhesive")
		(11 "B.Adhes" user "B.Adhesive")
		(13 "F.Paste" user "Package Geometry/Pastemask Top")
		(15 "B.Paste" user "Package Geometry/Pastemask Bottom")
		(5 "F.SilkS" user "Ref Des/Silkscreen Top")
		(7 "B.SilkS" user "Ref Des/Silkscreen Bottom")
		(1 "F.Mask" user "Board Geometry/Soldermask Top")
		(3 "B.Mask" user "Board Geometry/Soldermask Bottom")
		(17 "Dwgs.User" user "User.Drawings")
		(19 "Cmts.User" user "User.Comments")
		(21 "Eco1.User" user "User.Eco1")
		(23 "Eco2.User" user "User.Eco2")
		(25 "Edge.Cuts" user "Board Geometry/Outline")
		(27 "Margin" user)
		(31 "F.CrtYd" user "Package Geometry/Place Bound Top")
		(29 "B.CrtYd" user "Package Geometry/Place Bound Bottom")
		(35 "F.Fab" user "Ref Des/Assembly Top")
		(33 "B.Fab" user "Ref Des/Assembly Bottom")
	)
	(footprint ""
		(layer "F.Cu")
		(at 13.625322 -119.105426 90)
		(property "Reference" "R5864"
			(at 0 0 90)
			(layer "F.SilkS")
			(hide yes)
			(effects
				(font
					(size 1.27 1.27)
				)
			)
		)
		(property "Value" ""
			(at 0 0 90)
			(layer "F.Fab")
			(effects
				(font
					(size 1.27 1.27)
				)
			)
		)
		(duplicate_pad_numbers_are_jumpers no)
		(fp_line
			(start 0.7874 -0.4064)
			(end 0.7874 0.4064)
			(stroke
				(width 0.1524)
				(type default)
			)
			(layer "F.SilkS")
		)
		(fp_line
			(start -0.7874 -0.4064)
			(end 0.7874 -0.4064)
			(stroke
				(width 0.1524)
				(type default)
			)
			(layer "F.SilkS")
		)
		(fp_line
			(start 0.7874 0.4064)
			(end -0.7874 0.4064)
			(stroke
				(width 0.1524)
				(type default)
			)
			(layer "F.SilkS")
		)
		(fp_line
			(start -0.7874 0.4064)
			(end -0.7874 -0.4064)
			(stroke
				(width 0.1524)
				(type default)
			)
			(layer "F.SilkS")
		)
		(fp_line
			(start -0.12065 -0.305054)
			(end -0.12065 -0.2794)
			(stroke
				(width 0.1)
				(type default)
			)
			(layer "F.Fab")
		)
		(fp_line
			(start -0.67945 -0.305054)
			(end -0.12065 -0.305054)
			(stroke
				(width 0.1)
				(type default)
			)
			(layer "F.Fab")
		)
		(fp_line
			(start 0.67945 -0.3048)
			(end 0.67945 0.3048)
			(stroke
				(width 0.1)
				(type default)
			)
			(layer "F.Fab")
		)
		(fp_line
			(start 0.12065 -0.3048)
			(end 0.67945 -0.3048)
			(stroke
				(width 0.1)
				(type default)
			)
			(layer "F.Fab")
		)
		(fp_line
			(start 0.12065 -0.2794)
			(end 0.12065 -0.3048)
			(stroke
				(width 0.1)
				(type default)
			)
			(layer "F.Fab")
		)
		(fp_line
			(start -0.12065 -0.2794)
			(end 0.12065 -0.2794)
			(stroke
				(width 0.1)
				(type default)
			)
			(layer "F.Fab")
		)
		(fp_line
			(start 0.120396 0.2794)
			(end -0.12065 0.2794)
			(stroke
				(width 0.1)
				(type default)
			)
			(layer "F.Fab")
		)
		(fp_line
			(start -0.12065 0.2794)
			(end -0.12065 0.3048)
			(stroke
				(width 0.1)
				(type default)
			)
			(layer "F.Fab")
		)
		(fp_line
			(start 0.67945 0.3048)
			(end 0.120396 0.3048)
			(stroke
				(width 0.1)
				(type default)
			)
			(layer "F.Fab")
		)
		(fp_line
			(start 0.120396 0.3048)
			(end 0.120396 0.2794)
			(stroke
				(width 0.1)
				(type default)
			)
			(layer "F.Fab")
		)
		(fp_line
			(start -0.12065 0.3048)
			(end -0.67945 0.3048)
			(stroke
				(width 0.1)
				(type default)
			)
			(layer "F.Fab")
		)
		(fp_line
			(start -0.67945 0.3048)
			(end -0.67945 -0.305054)
			(stroke
				(width 0.1)
				(type default)
			)
			(layer "F.Fab")
		)
		(pad "1" smd circle
			(at -0.40005 0 90)
			(size 0 0)
			(layers "F.Cu" "F.Mask" "F.Paste")
			(net "P3V3_NIC0_PG_G1")
		)
		(pad "2" smd circle
			(at 0.40005 0 90)
			(size 0 0)
			(layers "F.Cu" "F.Mask" "F.Paste")
			(net "GND")
		)
	)
	(footprint ""
		(layer "F.Cu")
		(at 358.830626 -142.035276 180)
		(property "Reference" "PC335"
			(at 0 0 180)
			(layer "F.SilkS")
			(hide yes)
			(effects
				(font
					(size 1.27 1.27)
				)
			)
		)
		(property "Value" ""
			(at 0 0 180)
			(layer "F.Fab")
			(effects
				(font
					(size 1.27 1.27)
				)
			)
		)
		(duplicate_pad_numbers_are_jumpers no)
		(fp_line
			(start 1.524 0.762)
			(end -1.524 0.762)
			(stroke
				(width 0.1524)
				(type default)
			)
			(layer "F.SilkS")
		)
		(fp_line
			(start 1.524 -0.762)
			(end 1.524 0.762)
			(stroke
				(width 0.1524)
				(type default)
			)
			(layer "F.SilkS")
		)
		(fp_line
			(start -1.524 0.762)
			(end -1.524 -0.762)
			(stroke
				(width 0.1524)
				(type default)
			)
			(layer "F.SilkS")
		)
		(fp_line
			(start -1.524 -0.762)
			(end 1.524 -0.762)
			(stroke
				(width 0.1524)
				(type default)
			)
			(layer "F.SilkS")
		)
		(fp_line
			(start 1.1049 0.724916)
			(end 1.1049 -0.724916)
			(stroke
				(width 0.1)
				(type default)
			)
			(layer "F.Fab")
		)
		(fp_line
			(start 1.1049 -0.724916)
			(end -1.1049 -0.724916)
			(stroke
				(width 0.1)
				(type default)
			)
			(layer "F.Fab")
		)
		(fp_line
			(start -1.1049 0.724916)
			(end 1.1049 0.724916)
			(stroke
				(width 0.1)
				(type default)
			)
			(layer "F.Fab")
		)
		(fp_line
			(start -1.1049 -0.724916)
			(end -1.1049 0.724916)
			(stroke
				(width 0.1)
				(type default)
			)
			(layer "F.Fab")
		)
		(pad "1" smd rect
			(at -0.889 0)
			(size 1.016 1.27)
			(layers "F.Cu" "F.Mask" "F.Paste")
			(net "P12V_NIC6_R")
		)
		(pad "2" smd rect
			(at 0.889 0)
			(size 1.016 1.27)
			(layers "F.Cu" "F.Mask" "F.Paste")
			(net "GND")
		)
	)
	(footprint ""
		(layer "F.Cu")
		(at 486.553764 -528.154392 180)
		(property "Reference" "PEX1_HS"
			(at 0.127 -0.593598 0)
			(unlocked yes)
			(layer "F.SilkS")
			(effects
				(font
					(size 0.254 0.127)
					(thickness 0.000001)
				)
			)
		)
		(property "Value" ""
			(at 0 0 180)
			(layer "F.Fab")
			(effects
				(font
					(size 1.27 1.27)
				)
			)
		)
		(duplicate_pad_numbers_are_jumpers no)
		(pad "1" smd circle
			(at 0 0 180)
			(size 0.762 0.762)
			(layers "F.Cu" "F.Mask" "F.Paste")
			(net "Net_9123")
		)
	)
	(footprint ""
		(layer "F.Cu")
		(at 263.207246 -257.439414 -90)
		(property "Reference" "C3368"
			(at 0 0 270)
			(layer "F.SilkS")
			(hide yes)
			(effects
				(font
					(size 1.27 1.27)
				)
			)
		)
		(property "Value" ""
			(at 0 0 270)
			(layer "F.Fab")
			(effects
				(font
					(size 1.27 1.27)
				)
			)
		)
		(duplicate_pad_numbers_are_jumpers no)
		(fp_line
			(start -0.299974 0.150114)
			(end -0.299974 -0.150114)
			(stroke
				(width 0.1)
				(type default)
			)
			(layer "F.Fab")
		)
		(fp_line
			(start 0.299974 0.150114)
			(end -0.299974 0.150114)
			(stroke
				(width 0.1)
				(type default)
			)
			(layer "F.Fab")
		)
		(fp_line
			(start -0.299974 -0.150114)
			(end 0.299974 -0.150114)
			(stroke
				(width 0.1)
				(type default)
			)
			(layer "F.Fab")
		)
		(fp_line
			(start 0.299974 -0.150114)
			(end 0.299974 0.150114)
			(stroke
				(width 0.1)
				(type default)
			)
			(layer "F.Fab")
		)
		(pad "1" smd rect
			(at -0.2667 0 270)
			(size 0.3048 0.381)
			(layers "F.Cu" "F.Mask" "F.Paste")
			(net "P1V8_PLL0_PEX2")
		)
		(pad "2" smd rect
			(at 0.2667 0 270)
			(size 0.3048 0.381)
			(layers "F.Cu" "F.Mask" "F.Paste")
			(net "GND")
		)
	)
	(footprint ""
		(layer "F.Cu")
		(at 121.13514 -91.462606)
		(property "Reference" "R1556"
			(at 0 0 0)
			(layer "F.SilkS")
			(hide yes)
			(effects
				(font
					(size 1.27 1.27)
				)
			)
		)
		(property "Value" ""
			(at 0 0 0)
			(layer "F.Fab")
			(effects
				(font
					(size 1.27 1.27)
				)
			)
		)
		(duplicate_pad_numbers_are_jumpers no)
		(fp_line
			(start -0.7874 -0.4064)
			(end 0.7874 -0.4064)
			(stroke
				(width 0.1524)
				(type default)
			)
			(layer "F.SilkS")
		)
		(fp_line
			(start -0.7874 0.4064)
			(end -0.7874 -0.4064)
			(stroke
				(width 0.1524)
				(type default)
			)
			(layer "F.SilkS")
		)
		(fp_line
			(start 0.7874 -0.4064)
			(end 0.7874 0.4064)
			(stroke
				(width 0.1524)
				(type default)
			)
			(layer "F.SilkS")
		)
		(fp_line
			(start 0.7874 0.4064)
			(end -0.7874 0.4064)
			(stroke
				(width 0.1524)
				(type default)
			)
			(layer "F.SilkS")
		)
		(fp_line
			(start -0.67945 -0.305054)
			(end -0.12065 -0.305054)
			(stroke
				(width 0.1)
				(type default)
			)
			(layer "F.Fab")
		)
		(fp_line
			(start -0.67945 0.3048)
			(end -0.67945 -0.305054)
			(stroke
				(width 0.1)
				(type default)
			)
			(layer "F.Fab")
		)
		(fp_line
			(start -0.12065 -0.305054)
			(end -0.12065 -0.2794)
			(stroke
				(width 0.1)
				(type default)
			)
			(layer "F.Fab")
		)
		(fp_line
			(start -0.12065 -0.2794)
			(end 0.12065 -0.2794)
			(stroke
				(width 0.1)
				(type default)
			)
			(layer "F.Fab")
		)
		(fp_line
			(start -0.12065 0.2794)
			(end -0.12065 0.3048)
			(stroke
				(width 0.1)
				(type default)
			)
			(layer "F.Fab")
		)
		(fp_line
			(start -0.12065 0.3048)
			(end -0.67945 0.3048)
			(stroke
				(width 0.1)
				(type default)
			)
			(layer "F.Fab")
		)
		(fp_line
			(start 0.120396 0.2794)
			(end -0.12065 0.2794)
			(stroke
				(width 0.1)
				(type default)
			)
			(layer "F.Fab")
		)
		(fp_line
			(start 0.120396 0.3048)
			(end 0.120396 0.2794)
			(stroke
				(width 0.1)
				(type default)
			)
			(layer "F.Fab")
		)
		(fp_line
			(start 0.12065 -0.3048)
			(end 0.67945 -0.3048)
			(stroke
				(width 0.1)
				(type default)
			)
			(layer "F.Fab")
		)
		(fp_line
			(start 0.12065 -0.2794)
			(end 0.12065 -0.3048)
			(stroke
				(width 0.1)
				(type default)
			)
			(layer "F.Fab")
		)
		(fp_line
			(start 0.67945 -0.3048)
			(end 0.67945 0.3048)
			(stroke
				(width 0.1)
				(type default)
			)
			(layer "F.Fab")
		)
		(fp_line
			(start 0.67945 0.3048)
			(end 0.120396 0.3048)
			(stroke
				(width 0.1)
				(type default)
			)
			(layer "F.Fab")
		)
		(pad "1" smd circle
			(at -0.40005 0)
			(size 0 0)
			(layers "F.Cu" "F.Mask" "F.Paste")
			(net "P3V3_AUX")
		)
		(pad "2" smd circle
			(at 0.40005 0)
			(size 0 0)
			(layers "F.Cu" "F.Mask" "F.Paste")
			(net "SMB_BIC_I2C9_MUX0_SSD2_R_SCL")
		)
	)
	(footprint ""
		(layer "F.Cu")
		(at 33.287716 -294.819832)
		(property "Reference" "C3027"
			(at 0 0 0)
			(layer "F.SilkS")
			(hide yes)
			(effects
				(font
					(size 1.27 1.27)
				)
			)
		)
		(property "Value" ""
			(at 0 0 0)
			(layer "F.Fab")
			(effects
				(font
					(size 1.27 1.27)
				)
			)
		)
		(duplicate_pad_numbers_are_jumpers no)
		(fp_line
			(start -1.2954 -0.5842)
			(end 1.2954 -0.5842)
			(stroke
				(width 0.1524)
				(type default)
			)
			(layer "F.SilkS")
		)
		(fp_line
			(start -1.2954 0.5842)
			(end -1.2954 -0.5842)
			(stroke
				(width 0.1524)
				(type default)
			)
			(layer "F.SilkS")
		)
		(fp_line
			(start 1.2954 -0.5842)
			(end 1.2954 0.5842)
			(stroke
				(width 0.1524)
				(type default)
			)
			(layer "F.SilkS")
		)
		(fp_line
			(start 1.2954 0.5842)
			(end -1.2954 0.5842)
			(stroke
				(width 0.1524)
				(type default)
			)
			(layer "F.SilkS")
		)
		(fp_line
			(start -1.1938 -0.4064)
			(end -0.8636 -0.4064)
			(stroke
				(width 0.1)
				(type default)
			)
			(layer "F.Fab")
		)
		(fp_line
			(start -1.1938 0.4064)
			(end -1.1938 -0.4064)
			(stroke
				(width 0.1)
				(type default)
			)
			(layer "F.Fab")
		)
		(fp_line
			(start -0.8636 -0.4572)
			(end 0.8636 -0.4572)
			(stroke
				(width 0.1)
				(type default)
			)
			(layer "F.Fab")
		)
		(fp_line
			(start -0.8636 -0.4064)
			(end -0.8636 -0.4572)
			(stroke
				(width 0.1)
				(type default)
			)
			(layer "F.Fab")
		)
		(fp_line
			(start -0.8636 0.4064)
			(end -1.1938 0.4064)
			(stroke
				(width 0.1)
				(type default)
			)
			(layer "F.Fab")
		)
		(fp_line
			(start -0.8636 0.4572)
			(end -0.8636 0.4064)
			(stroke
				(width 0.1)
				(type default)
			)
			(layer "F.Fab")
		)
		(fp_line
			(start 0.8636 -0.4572)
			(end 0.8636 -0.4064)
			(stroke
				(width 0.1)
				(type default)
			)
			(layer "F.Fab")
		)
		(fp_line
			(start 0.8636 -0.4064)
			(end 1.1938 -0.4064)
			(stroke
				(width 0.1)
				(type default)
			)
			(layer "F.Fab")
		)
		(fp_line
			(start 0.8636 0.4064)
			(end 0.8636 0.4572)
			(stroke
				(width 0.1)
				(type default)
			)
			(layer "F.Fab")
		)
		(fp_line
			(start 0.8636 0.4572)
			(end -0.8636 0.4572)
			(stroke
				(width 0.1)
				(type default)
			)
			(layer "F.Fab")
		)
		(fp_line
			(start 1.1938 -0.4064)
			(end 1.1938 0.4064)
			(stroke
				(width 0.1)
				(type default)
			)
			(layer "F.Fab")
		)
		(fp_line
			(start 1.1938 0.4064)
			(end 0.8636 0.4064)
			(stroke
				(width 0.1)
				(type default)
			)
			(layer "F.Fab")
		)
		(pad "1" smd rect
			(at -0.7366 0 270)
			(size 0.7112 0.8128)
			(layers "F.Cu" "F.Mask" "F.Paste")
			(net "PCEPLL2_VDDA18_PEX0")
		)
		(pad "2" smd rect
			(at 0.7366 0 270)
			(size 0.7112 0.8128)
			(layers "F.Cu" "F.Mask" "F.Paste")
			(net "GND")
		)
	)
	(footprint ""
		(layer "F.Cu")
		(at 104.267 -57.332626)
		(property "Reference" "R6838"
			(at 0 0 0)
			(layer "F.SilkS")
			(hide yes)
			(effects
				(font
					(size 1.27 1.27)
				)
			)
		)
		(property "Value" ""
			(at 0 0 0)
			(layer "F.Fab")
			(effects
				(font
					(size 1.27 1.27)
				)
			)
		)
		(duplicate_pad_numbers_are_jumpers no)
		(fp_line
			(start -0.7874 -0.4064)
			(end 0.7874 -0.4064)
			(stroke
				(width 0.1524)
				(type default)
			)
			(layer "F.SilkS")
		)
		(fp_line
			(start -0.7874 0.4064)
			(end -0.7874 -0.4064)
			(stroke
				(width 0.1524)
				(type default)
			)
			(layer "F.SilkS")
		)
		(fp_line
			(start 0.7874 -0.4064)
			(end 0.7874 0.4064)
			(stroke
				(width 0.1524)
				(type default)
			)
			(layer "F.SilkS")
		)
		(fp_line
			(start 0.7874 0.4064)
			(end -0.7874 0.4064)
			(stroke
				(width 0.1524)
				(type default)
			)
			(layer "F.SilkS")
		)
		(fp_line
			(start -0.67945 -0.305054)
			(end -0.12065 -0.305054)
			(stroke
				(width 0.1)
				(type default)
			)
			(layer "F.Fab")
		)
		(fp_line
			(start -0.67945 0.3048)
			(end -0.67945 -0.305054)
			(stroke
				(width 0.1)
				(type default)
			)
			(layer "F.Fab")
		)
		(fp_line
			(start -0.12065 -0.305054)
			(end -0.12065 -0.2794)
			(stroke
				(width 0.1)
				(type default)
			)
			(layer "F.Fab")
		)
		(fp_line
			(start -0.12065 -0.2794)
			(end 0.12065 -0.2794)
			(stroke
				(width 0.1)
				(type default)
			)
			(layer "F.Fab")
		)
		(fp_line
			(start -0.12065 0.2794)
			(end -0.12065 0.3048)
			(stroke
				(width 0.1)
				(type default)
			)
			(layer "F.Fab")
		)
		(fp_line
			(start -0.12065 0.3048)
			(end -0.67945 0.3048)
			(stroke
				(width 0.1)
				(type default)
			)
			(layer "F.Fab")
		)
		(fp_line
			(start 0.120396 0.2794)
			(end -0.12065 0.2794)
			(stroke
				(width 0.1)
				(type default)
			)
			(layer "F.Fab")
		)
		(fp_line
			(start 0.120396 0.3048)
			(end 0.120396 0.2794)
			(stroke
				(width 0.1)
				(type default)
			)
			(layer "F.Fab")
		)
		(fp_line
			(start 0.12065 -0.3048)
			(end 0.67945 -0.3048)
			(stroke
				(width 0.1)
				(type default)
			)
			(layer "F.Fab")
		)
		(fp_line
			(start 0.12065 -0.2794)
			(end 0.12065 -0.3048)
			(stroke
				(width 0.1)
				(type default)
			)
			(layer "F.Fab")
		)
		(fp_line
			(start 0.67945 -0.3048)
			(end 0.67945 0.3048)
			(stroke
				(width 0.1)
				(type default)
			)
			(layer "F.Fab")
		)
		(fp_line
			(start 0.67945 0.3048)
			(end 0.120396 0.3048)
			(stroke
				(width 0.1)
				(type default)
			)
			(layer "F.Fab")
		)
		(pad "1" smd circle
			(at -0.40005 0)
			(size 0 0)
			(layers "F.Cu" "F.Mask" "F.Paste")
			(net "SSD3_PWR_EN_R")
		)
		(pad "2" smd circle
			(at 0.40005 0)
			(size 0 0)
			(layers "F.Cu" "F.Mask" "F.Paste")
			(net "GND")
		)
	)
	(footprint ""
		(layer "F.Cu")
		(at 420.975028 -56.977534 180)
		(property "Reference" "PC426"
			(at 0 0 180)
			(layer "F.SilkS")
			(hide yes)
			(effects
				(font
					(size 1.27 1.27)
				)
			)
		)
		(property "Value" ""
			(at 0 0 180)
			(layer "F.Fab")
			(effects
				(font
					(size 1.27 1.27)
				)
			)
		)
		(duplicate_pad_numbers_are_jumpers no)
		(fp_line
			(start 0.7874 0.4064)
			(end -0.7874 0.4064)
			(stroke
				(width 0.1524)
				(type default)
			)
			(layer "F.SilkS")
		)
		(fp_line
			(start 0.7874 -0.4064)
			(end 0.7874 0.4064)
			(stroke
				(width 0.1524)
				(type default)
			)
			(layer "F.SilkS")
		)
		(fp_line
			(start -0.7874 0.4064)
			(end -0.7874 -0.4064)
			(stroke
				(width 0.1524)
				(type default)
			)
			(layer "F.SilkS")
		)
		(fp_line
			(start -0.7874 -0.4064)
			(end 0.7874 -0.4064)
			(stroke
				(width 0.1524)
				(type default)
			)
			(layer "F.SilkS")
		)
		(fp_line
			(start 0.67945 0.3048)
			(end 0.120396 0.3048)
			(stroke
				(width 0.1)
				(type default)
			)
			(layer "F.Fab")
		)
		(fp_line
			(start 0.67945 -0.3048)
			(end 0.67945 0.3048)
			(stroke
				(width 0.1)
				(type default)
			)
			(layer "F.Fab")
		)
		(fp_line
			(start 0.12065 -0.2794)
			(end 0.12065 -0.3048)
			(stroke
				(width 0.1)
				(type default)
			)
			(layer "F.Fab")
		)
		(fp_line
			(start 0.12065 -0.3048)
			(end 0.67945 -0.3048)
			(stroke
				(width 0.1)
				(type default)
			)
			(layer "F.Fab")
		)
		(fp_line
			(start 0.120396 0.3048)
			(end 0.120396 0.2794)
			(stroke
				(width 0.1)
				(type default)
			)
			(layer "F.Fab")
		)
		(fp_line
			(start 0.120396 0.2794)
			(end -0.12065 0.2794)
			(stroke
				(width 0.1)
				(type default)
			)
			(layer "F.Fab")
		)
		(fp_line
			(start -0.12065 0.3048)
			(end -0.67945 0.3048)
			(stroke
				(width 0.1)
				(type default)
			)
			(layer "F.Fab")
		)
		(fp_line
			(start -0.12065 0.2794)
			(end -0.12065 0.3048)
			(stroke
				(width 0.1)
				(type default)
			)
			(layer "F.Fab")
		)
		(fp_line
			(start -0.12065 -0.2794)
			(end 0.12065 -0.2794)
			(stroke
				(width 0.1)
				(type default)
			)
			(layer "F.Fab")
		)
		(fp_line
			(start -0.12065 -0.305054)
			(end -0.12065 -0.2794)
			(stroke
				(width 0.1)
				(type default)
			)
			(layer "F.Fab")
		)
		(fp_line
			(start -0.67945 0.3048)
			(end -0.67945 -0.305054)
			(stroke
				(width 0.1)
				(type default)
			)
			(layer "F.Fab")
		)
		(fp_line
			(start -0.67945 -0.305054)
			(end -0.12065 -0.305054)
			(stroke
				(width 0.1)
				(type default)
			)
			(layer "F.Fab")
		)
		(pad "1" smd circle
			(at -0.40005 0 180)
			(size 0 0)
			(layers "F.Cu" "F.Mask" "F.Paste")
			(net "P12V_AUX")
		)
		(pad "2" smd circle
			(at 0.40005 0 180)
			(size 0 0)
			(layers "F.Cu" "F.Mask" "F.Paste")
			(net "GND")
		)
	)
)
